(kicad_pcb
	(version 20241229)
	(generator "pcbnew")
	(generator_version "9.0")
	(general
		(thickness 1.6296)
		(legacy_teardrops no)
	)
	(paper "A3")
	(title_block
		(title "Thunderbolt to 10GbE adapter")
		(date "2026-04-21")
		(rev "1.1.0")
		(company "Antmicro Ltd")
		(comment 1 "www.antmicro.com")
		(comment 9 "footprints 516-519 of 703")
	)
	(layers
		(0 "F.Cu" signal)
		(4 "In1.Cu" signal)
		(6 "In2.Cu" signal)
		(8 "In3.Cu" signal)
		(10 "In4.Cu" signal)
		(12 "In5.Cu" signal)
		(14 "In6.Cu" signal)
		(2 "B.Cu" signal)
		(9 "F.Adhes" user "F.Adhesive")
		(11 "B.Adhes" user "B.Adhesive")
		(13 "F.Paste" user)
		(15 "B.Paste" user)
		(5 "F.SilkS" user "F.Silkscreen")
		(7 "B.SilkS" user "B.Silkscreen")
		(1 "F.Mask" user)
		(3 "B.Mask" user)
		(17 "Dwgs.User" user "User.Drawings")
		(19 "Cmts.User" user "User.Comments")
		(21 "Eco1.User" user "User.Eco1")
		(23 "Eco2.User" user "User.Eco2")
		(25 "Edge.Cuts" user)
		(27 "Margin" user)
		(31 "F.CrtYd" user "F.Courtyard")
		(29 "B.CrtYd" user "B.Courtyard")
		(35 "F.Fab" user)
		(33 "B.Fab" user)
	)
	(footprint "antmicro-footprints:C_0402_1005Metric"
		(layer "B.Cu")
		(at 128.1 129.3)
		(descr "Capacitor SMD 0402")
		(tags "capacitor SMD 0402")
		(property "Reference" "C95"
			(at 21.6 -7.7 180)
			(layer "B.SilkS")
			(effects
				(font
					(size 0.7 0.7)
					(thickness 0.15)
				)
				(justify mirror)
			)
		)
		(property "Value" "C_10u_0402"
			(at -1.022927 -2.155213 180)
			(layer "B.Fab")
			(effects
				(font
					(size 0.7 0.7)
					(thickness 0.15)
				)
				(justify left bottom mirror)
			)
		)
		(property "Datasheet" "https://www.yageo.com/en/Chart/Download/pdf/CC0402MRX5R5BB106"
			(at 0 0 180)
			(layer "B.Fab")
			(hide yes)
			(effects
				(font
					(size 1.27 1.27)
					(thickness 0.15)
				)
				(justify mirror)
			)
		)
		(property "Description" "SMD Multilayer Ceramic Capacitor, 10 µF, 6.3 V, 0402 [1005 Metric], ± 20%, X5R, CC Series"
			(at 0 0 180)
			(layer "B.Fab")
			(hide yes)
			(effects
				(font
					(size 1.27 1.27)
					(thickness 0.15)
				)
				(justify mirror)
			)
		)
		(property "MPN" "CC0402MRX5R5BB106"
			(at 0 0 0)
			(unlocked yes)
			(layer "B.Fab")
			(hide yes)
			(effects
				(font
					(size 1 1)
					(thickness 0.15)
				)
				(justify mirror)
			)
		)
		(property "Manufacturer" "YAGEO"
			(at 0 0 0)
			(unlocked yes)
			(layer "B.Fab")
			(hide yes)
			(effects
				(font
					(size 1 1)
					(thickness 0.15)
				)
				(justify mirror)
			)
		)
		(property "License" "Apache-2.0"
			(at 0 0 0)
			(unlocked yes)
			(layer "B.Fab")
			(hide yes)
			(effects
				(font
					(size 1 1)
					(thickness 0.15)
				)
				(justify mirror)
			)
		)
		(property "Val" "10u"
			(at 0 0 0)
			(unlocked yes)
			(layer "B.Fab")
			(hide yes)
			(effects
				(font
					(size 1 1)
					(thickness 0.15)
				)
				(justify mirror)
			)
		)
		(property "Voltage" ""
			(at 0 0 0)
			(unlocked yes)
			(layer "B.Fab")
			(hide yes)
			(effects
				(font
					(size 1 1)
					(thickness 0.15)
				)
				(justify mirror)
			)
		)
		(property "Dielectric" ""
			(at 0 0 0)
			(unlocked yes)
			(layer "B.Fab")
			(hide yes)
			(effects
				(font
					(size 1 1)
					(thickness 0.15)
				)
				(justify mirror)
			)
		)
		(property "Author" "Antmicro"
			(at 0 0 0)
			(unlocked yes)
			(layer "B.Fab")
			(hide yes)
			(effects
				(font
					(size 1 1)
					(thickness 0.15)
				)
				(justify mirror)
			)
		)
		(sheetname "/TB Controller - Power/")
		(sheetfile "tb-power.kicad_sch")
		(attr smd)
		(fp_rect
			(start -0.925 0.47)
			(end 0.925 -0.47)
			(stroke
				(width 0.05)
				(type default)
			)
			(fill no)
			(layer "B.CrtYd")
		)
		(fp_line
			(start -0.494 -0.248)
			(end -0.494 0.25)
			(stroke
				(width 0.15)
				(type solid)
			)
			(layer "B.Fab")
		)
		(fp_line
			(start -0.494 0.25)
			(end 0.504 0.25)
			(stroke
				(width 0.15)
				(type solid)
			)
			(layer "B.Fab")
		)
		(fp_line
			(start 0.504 -0.248)
			(end -0.494 -0.248)
			(stroke
				(width 0.15)
				(type solid)
			)
			(layer "B.Fab")
		)
		(fp_line
			(start 0.504 0.25)
			(end 0.504 -0.248)
			(stroke
				(width 0.15)
				(type solid)
			)
			(layer "B.Fab")
		)
		(fp_text user "${REFERENCE}"
			(at -0.939 -4.599 180)
			(layer "B.Fab")
			(effects
				(font
					(size 0.7 0.7)
					(thickness 0.15)
				)
				(justify left bottom mirror)
			)
		)
		(fp_text user "License: Apache-2.0"
			(at -0.939 -5.799 180)
			(layer "B.Fab")
			(effects
				(font
					(size 0.7 0.7)
					(thickness 0.15)
				)
				(justify left bottom mirror)
			)
		)
		(fp_text user "Author: Antmicro"
			(at -0.939 -3.399 180)
			(layer "B.Fab")
			(effects
				(font
					(size 0.7 0.7)
					(thickness 0.15)
				)
				(justify left bottom mirror)
			)
		)
		(pad "1" smd roundrect
			(at -0.48 0)
			(size 0.59 0.64)
			(layers "B.Cu" "B.Mask" "B.Paste")
			(roundrect_rratio 0.25)
			(net 23 "GND")
			(pintype "passive")
		)
		(pad "2" smd roundrect
			(at 0.48 0)
			(size 0.59 0.64)
			(layers "B.Cu" "B.Mask" "B.Paste")
			(roundrect_rratio 0.25)
			(net 180 "Net-(U4A-VCC0P9_LVR_SENSE)")
			(pintype "passive")
		)
	)
	(footprint "antmicro-footprints:L_0603_1608Metric"
		(layer "B.Cu")
		(at 126.309999 117.589999 -90)
		(property "Reference" "L3"
			(at -7.700002 -21.900002 90)
			(layer "B.SilkS")
			(effects
				(font
					(size 0.7 0.7)
					(thickness 0.15)
				)
				(justify mirror)
			)
		)
		(property "Value" "L_1u_1.8A_0603"
			(at 0 -2 90)
			(layer "B.Fab")
			(effects
				(font
					(size 0.7 0.7)
					(thickness 0.15)
				)
				(justify left bottom mirror)
			)
		)
		(property "Datasheet" "https://search.murata.co.jp/Ceramy/image/img/P02/JETE243A-0041.pdf"
			(at 0 0 90)
			(layer "B.Fab")
			(hide yes)
			(effects
				(font
					(size 1.27 1.27)
					(thickness 0.15)
				)
				(justify mirror)
			)
		)
		(property "Description" "Power Inductor (SMT), 1 µH, 1.8 A, Shielded, 1.9 A, DFE Series, 0603 [1608 Metric]"
			(at 0 0 90)
			(layer "B.Fab")
			(hide yes)
			(effects
				(font
					(size 1.27 1.27)
					(thickness 0.15)
				)
				(justify mirror)
			)
		)
		(property "Val" "1u/1.8A"
			(at 0 0 270)
			(unlocked yes)
			(layer "B.Fab")
			(hide yes)
			(effects
				(font
					(size 1 1)
					(thickness 0.15)
				)
				(justify mirror)
			)
		)
		(property "Manufacturer" "Murata"
			(at 0 0 270)
			(unlocked yes)
			(layer "B.Fab")
			(hide yes)
			(effects
				(font
					(size 1 1)
					(thickness 0.15)
				)
				(justify mirror)
			)
		)
		(property "MPN" "DFE18SBN1R0ME0L"
			(at 0 0 270)
			(unlocked yes)
			(layer "B.Fab")
			(hide yes)
			(effects
				(font
					(size 1 1)
					(thickness 0.15)
				)
				(justify mirror)
			)
		)
		(property "ISat" "1.9A"
			(at 0 0 270)
			(unlocked yes)
			(layer "B.Fab")
			(hide yes)
			(effects
				(font
					(size 1 1)
					(thickness 0.15)
				)
				(justify mirror)
			)
		)
		(property "IMax" "1.8A"
			(at 0 0 270)
			(unlocked yes)
			(layer "B.Fab")
			(hide yes)
			(effects
				(font
					(size 1 1)
					(thickness 0.15)
				)
				(justify mirror)
			)
		)
		(property "Size" "1.6x0.8"
			(at 0 0 270)
			(unlocked yes)
			(layer "B.Fab")
			(hide yes)
			(effects
				(font
					(size 1 1)
					(thickness 0.15)
				)
				(justify mirror)
			)
		)
		(property "License" "Apache-2.0"
			(at 0 0 270)
			(unlocked yes)
			(layer "B.Fab")
			(hide yes)
			(effects
				(font
					(size 1 1)
					(thickness 0.15)
				)
				(justify mirror)
			)
		)
		(property "Author" "Antmicro"
			(at 0 0 270)
			(unlocked yes)
			(layer "B.Fab")
			(hide yes)
			(effects
				(font
					(size 1 1)
					(thickness 0.15)
				)
				(justify mirror)
			)
		)
		(sheetname "/TB Controller - Power/")
		(sheetfile "tb-power.kicad_sch")
		(attr smd)
		(fp_line
			(start -0.15 0.4)
			(end 0.15 0.4)
			(stroke
				(width 0.15)
				(type solid)
			)
			(layer "B.SilkS")
		)
		(fp_line
			(start -0.15 -0.4)
			(end 0.15 -0.4)
			(stroke
				(width 0.15)
				(type solid)
			)
			(layer "B.SilkS")
		)
		(fp_rect
			(start -1.25 0.65)
			(end 1.25 -0.65)
			(stroke
				(width 0.05)
				(type solid)
			)
			(fill no)
			(layer "B.CrtYd")
		)
		(fp_rect
			(start -0.8 0.4)
			(end 0.8 -0.4)
			(stroke
				(width 0.1)
				(type solid)
			)
			(fill no)
			(layer "B.Fab")
		)
		(fp_text user "${REFERENCE}"
			(at -1.9 -3.1 90)
			(layer "B.Fab")
			(effects
				(font
					(size 0.7 0.7)
					(thickness 0.15)
				)
				(justify left bottom mirror)
			)
		)
		(fp_text user "License: Apache-2.0"
			(at -1.9 -5.75 90)
			(layer "B.Fab")
			(effects
				(font
					(size 0.7 0.7)
					(thickness 0.15)
				)
				(justify left bottom mirror)
			)
		)
		(fp_text user "Author: Antmicro"
			(at -1.9 -4.4 90)
			(layer "B.Fab")
			(effects
				(font
					(size 0.7 0.7)
					(thickness 0.15)
				)
				(justify left bottom mirror)
			)
		)
		(pad "1" smd roundrect
			(at -0.7 0 270)
			(size 0.8 1)
			(layers "B.Cu" "B.Mask" "B.Paste")
			(roundrect_rratio 0.2)
			(net 181 "Net-(U4A-VCC3P3_S0)")
			(pintype "passive")
		)
		(pad "2" smd roundrect
			(at 0.7 0 270)
			(size 0.8 1)
			(layers "B.Cu" "B.Mask" "B.Paste")
			(roundrect_rratio 0.2)
			(net 57 "+3V3_TB")
			(pintype "passive")
		)
	)
	(footprint "antmicro-footprints:R_0402_1005Metric"
		(layer "B.Cu")
		(at 153.031866 82.235117 180)
		(descr "Resistor SMD 0402")
		(tags "resistor SMD 0402")
		(property "Reference" "R129"
			(at -20.368136 -9.464883 0)
			(layer "B.SilkS")
			(effects
				(font
					(size 0.7 0.7)
					(thickness 0.15)
				)
				(justify mirror)
			)
		)
		(property "Value" "R_1k_0402"
			(at -1.011843 -1.772047 0)
			(layer "B.Fab")
			(effects
				(font
					(size 0.7 0.7)
					(thickness 0.15)
				)
				(justify left bottom mirror)
			)
		)
		(property "Datasheet" "https://www.bourns.com/docs/product-datasheets/cr.pdf"
			(at 0 0 0)
			(layer "B.Fab")
			(hide yes)
			(effects
				(font
					(size 1.27 1.27)
					(thickness 0.15)
				)
				(justify mirror)
			)
		)
		(property "Description" "SMD Chip Resistor, 1 kohm, ± 1%, 63 mW, 0402 [1005 Metric], Thick Film, General Purpose"
			(at 0 0 0)
			(layer "B.Fab")
			(hide yes)
			(effects
				(font
					(size 1.27 1.27)
					(thickness 0.15)
				)
				(justify mirror)
			)
		)
		(property "MPN" "CR0402-FX-1001GLF"
			(at 0 0 180)
			(unlocked yes)
			(layer "B.Fab")
			(hide yes)
			(effects
				(font
					(size 1 1)
					(thickness 0.15)
				)
				(justify mirror)
			)
		)
		(property "Manufacturer" "Bourns"
			(at 0 0 180)
			(unlocked yes)
			(layer "B.Fab")
			(hide yes)
			(effects
				(font
					(size 1 1)
					(thickness 0.15)
				)
				(justify mirror)
			)
		)
		(property "License" "Apache-2.0"
			(at 0 0 180)
			(unlocked yes)
			(layer "B.Fab")
			(hide yes)
			(effects
				(font
					(size 1 1)
					(thickness 0.15)
				)
				(justify mirror)
			)
		)
		(property "Author" "Antmicro"
			(at 0 0 180)
			(unlocked yes)
			(layer "B.Fab")
			(hide yes)
			(effects
				(font
					(size 1 1)
					(thickness 0.15)
				)
				(justify mirror)
			)
		)
		(property "Val" "1k"
			(at 0 0 180)
			(unlocked yes)
			(layer "B.Fab")
			(hide yes)
			(effects
				(font
					(size 1 1)
					(thickness 0.15)
				)
				(justify mirror)
			)
		)
		(property "Tolerance" "1%"
			(at 0 0 180)
			(unlocked yes)
			(layer "B.Fab")
			(hide yes)
			(effects
				(font
					(size 1 1)
					(thickness 0.15)
				)
				(justify mirror)
			)
		)
		(sheetname "/X710-AT2 RSVD/")
		(sheetfile "x710-at2-rsvd.kicad_sch")
		(attr smd)
		(fp_rect
			(start -0.925 0.47)
			(end 0.925 -0.47)
			(stroke
				(width 0.05)
				(type default)
			)
			(fill no)
			(layer "B.CrtYd")
		)
		(fp_rect
			(start -0.5 0.25)
			(end 0.5 -0.25)
			(stroke
				(width 0.15)
				(type solid)
			)
			(fill no)
			(layer "B.Fab")
		)
		(fp_text user "${REFERENCE}"
			(at -0.95 -3.168 0)
			(layer "B.Fab")
			(effects
				(font
					(size 0.7 0.7)
					(thickness 0.15)
				)
				(justify left bottom mirror)
			)
		)
		(fp_text user "License: Apache-2.0"
			(at -0.95 -5.169 0)
			(layer "B.Fab")
			(effects
				(font
					(size 0.7 0.7)
					(thickness 0.15)
				)
				(justify left bottom mirror)
			)
		)
		(fp_text user "Author: Antmicro"
			(at -0.95 -4.169 0)
			(layer "B.Fab")
			(effects
				(font
					(size 0.7 0.7)
					(thickness 0.15)
				)
				(justify left bottom mirror)
			)
		)
		(pad "1" smd roundrect
			(at -0.48 0 180)
			(size 0.59 0.64)
			(layers "B.Cu" "B.Mask" "B.Paste")
			(roundrect_rratio 0.25)
			(net 129 "/X710-AT2 RSVD/RSVDE19_1P88V")
			(pintype "passive")
		)
		(pad "2" smd roundrect
			(at 0.48 0 180)
			(size 0.59 0.64)
			(layers "B.Cu" "B.Mask" "B.Paste")
			(roundrect_rratio 0.25)
			(net 18 "+1V88")
			(pintype "passive")
		)
	)
	(footprint "antmicro-footprints:C_Pol_EIA-A"
		(layer "B.Cu")
		(at 143.2 99.5 90)
		(property "Reference" "C157"
			(at 0 1.2 90)
			(layer "B.SilkS")
			(effects
				(font
					(size 0.7 0.7)
					(thickness 0.15)
				)
				(justify right top mirror)
			)
		)
		(property "Value" "C_Pol_100u_6V_KEMET-T490-A"
			(at 0 -2 90)
			(layer "B.Fab")
			(effects
				(font
					(size 0.7 0.7)
					(thickness 0.15)
				)
				(justify right top mirror)
			)
		)
		(property "Datasheet" "https://www.kemet.com/en/us/capacitors/product/T490A107M006ATE800.html"
			(at 0 0 90)
			(layer "B.Fab")
			(hide yes)
			(effects
				(font
					(size 1.27 1.27)
					(thickness 0.15)
				)
				(justify mirror)
			)
		)
		(property "Description" "Surface Mount Tantalum Capacitor,  Solid SMD 6V 100uF 1206 20% ESR=800mOhms"
			(at 0 0 90)
			(layer "B.Fab")
			(hide yes)
			(effects
				(font
					(size 1.27 1.27)
					(thickness 0.15)
				)
				(justify mirror)
			)
		)
		(property "Val" "100u"
			(at 0 0 90)
			(unlocked yes)
			(layer "B.Fab")
			(hide yes)
			(effects
				(font
					(size 1 1)
					(thickness 0.15)
				)
				(justify mirror)
			)
		)
		(property "MPN" "T490A107M006ATE800"
			(at 0 0 90)
			(unlocked yes)
			(layer "B.Fab")
			(hide yes)
			(effects
				(font
					(size 1 1)
					(thickness 0.15)
				)
				(justify mirror)
			)
		)
		(property "Manufacturer" "KEMET"
			(at 0 0 90)
			(unlocked yes)
			(layer "B.Fab")
			(hide yes)
			(effects
				(font
					(size 1 1)
					(thickness 0.15)
				)
				(justify mirror)
			)
		)
		(property "License" "Apache-2.0"
			(at 0 0 90)
			(unlocked yes)
			(layer "B.Fab")
			(hide yes)
			(effects
				(font
					(size 1 1)
					(thickness 0.15)
				)
				(justify mirror)
			)
		)
		(property "Author" "Antmicro"
			(at 0 0 90)
			(unlocked yes)
			(layer "B.Fab")
			(hide yes)
			(effects
				(font
					(size 1 1)
					(thickness 0.15)
				)
				(justify mirror)
			)
		)
		(property "Voltage" "6V"
			(at 0 0 90)
			(unlocked yes)
			(layer "B.Fab")
			(hide yes)
			(effects
				(font
					(size 1 1)
					(thickness 0.15)
				)
				(justify mirror)
			)
		)
		(property "Dielectric" "template_dielectric"
			(at 0 0 90)
			(unlocked yes)
			(layer "B.Fab")
			(hide yes)
			(effects
				(font
					(size 1 1)
					(thickness 0.15)
				)
				(justify mirror)
			)
		)
		(sheetname "/X710-AT2 power/")
		(sheetfile "x710-at2-power.kicad_sch")
		(attr smd)
		(fp_line
			(start 1.5 -0.85)
			(end -1.5 -0.85)
			(stroke
				(width 0.12)
				(type solid)
			)
			(layer "B.SilkS")
		)
		(fp_line
			(start 1.5 -0.75)
			(end 1.5 -0.85)
			(stroke
				(width 0.12)
				(type solid)
			)
			(layer "B.SilkS")
		)
		(fp_line
			(start -1.5 -0.75)
			(end -1.5 -0.85)
			(stroke
				(width 0.12)
				(type solid)
			)
			(layer "B.SilkS")
		)
		(fp_line
			(start 1.5 0.75)
			(end 1.5 0.85)
			(stroke
				(width 0.12)
				(type solid)
			)
			(layer "B.SilkS")
		)
		(fp_line
			(start -1.5 0.75)
			(end -1.5 0.85)
			(stroke
				(width 0.12)
				(type solid)
			)
			(layer "B.SilkS")
		)
		(fp_line
			(start -1.5 0.85)
			(end 1.5 0.85)
			(stroke
				(width 0.12)
				(type solid)
			)
			(layer "B.SilkS")
		)
		(fp_line
			(start -2.1 1.1)
			(end -1.8 1.1)
			(stroke
				(width 0.12)
				(type solid)
			)
			(layer "B.SilkS")
		)
		(fp_line
			(start -1.95 1.25)
			(end -1.95 0.95)
			(stroke
				(width 0.12)
				(type solid)
			)
			(layer "B.SilkS")
		)
		(fp_line
			(start 1.7 -1.05)
			(end -1.7 -1.05)
			(stroke
				(width 0.05)
				(type solid)
			)
			(layer "B.CrtYd")
		)
		(fp_line
			(start 1.7 -1.05)
			(end 1.7 -0.85)
			(stroke
				(width 0.05)
				(type solid)
			)
			(layer "B.CrtYd")
		)
		(fp_line
			(start -1.7 -1.05)
			(end -1.7 -0.85)
			(stroke
				(width 0.05)
				(type solid)
			)
			(layer "B.CrtYd")
		)
		(fp_line
			(start 2.05 -0.85)
			(end 1.7 -0.85)
			(stroke
				(width 0.05)
				(type solid)
			)
			(layer "B.CrtYd")
		)
		(fp_line
			(start -1.7 -0.85)
			(end -2.05 -0.85)
			(stroke
				(width 0.05)
				(type solid)
			)
			(layer "B.CrtYd")
		)
		(fp_line
			(start 2.05 0.85)
			(end 2.05 -0.85)
			(stroke
				(width 0.05)
				(type solid)
			)
			(layer "B.CrtYd")
		)
		(fp_line
			(start 2.05 0.85)
			(end 1.7 0.85)
			(stroke
				(width 0.05)
				(type solid)
			)
			(layer "B.CrtYd")
		)
		(fp_line
			(start 1.7 0.85)
			(end 1.7 1.05)
			(stroke
				(width 0.05)
				(type solid)
			)
			(layer "B.CrtYd")
		)
		(fp_line
			(start -1.7 0.85)
			(end -2.05 0.85)
			(stroke
				(width 0.05)
				(type solid)
			)
			(layer "B.CrtYd")
		)
		(fp_line
			(start -1.7 0.85)
			(end -1.7 1.05)
			(stroke
				(width 0.05)
				(type solid)
			)
			(layer "B.CrtYd")
		)
		(fp_line
			(start -2.05 0.85)
			(end -2.05 -0.85)
			(stroke
				(width 0.05)
				(type solid)
			)
			(layer "B.CrtYd")
		)
		(fp_line
			(start 1.7 1.05)
			(end -1.7 1.05)
			(stroke
				(width 0.05)
				(type solid)
			)
			(layer "B.CrtYd")
		)
		(fp_rect
			(start -1.601 0.802)
			(end 1.6 -0.8)
			(stroke
				(width 0.1)
				(type solid)
			)
			(fill no)
			(layer "B.Fab")
		)
		(fp_text user "License: Apache-2.0"
			(at -2.1 -5.198 90)
			(layer "B.Fab")
			(effects
				(font
					(size 0.7 0.7)
					(thickness 0.15)
				)
				(justify right top mirror)
			)
		)
		(fp_text user "${REFERENCE}"
			(at -2.1 -4.198 90)
			(layer "B.Fab")
			(effects
				(font
					(size 0.7 0.7)
					(thickness 0.15)
				)
				(justify right top mirror)
			)
		)
		(fp_text user "Author: Antmicro"
			(at -2.1 -6.198 90)
			(layer "B.Fab")
			(effects
				(font
					(size 0.7 0.7)
					(thickness 0.15)
				)
				(justify right top mirror)
			)
		)
		(pad "1" smd roundrect
			(at -1.2 0 90)
			(size 1.2 1.2)
			(layers "B.Cu" "B.Mask" "B.Paste")
			(roundrect_rratio 0.1)
			(net 6 "DVDD")
			(pintype "passive")
		)
		(pad "2" smd roundrect
			(at 1.2 0 90)
			(size 1.2 1.2)
			(layers "B.Cu" "B.Mask" "B.Paste")
			(roundrect_rratio 0.1)
			(net 23 "GND")
			(pintype "passive")
		)
	)
)
